(kicad_pcb
	(version 20260206)
	(generator "pcbnew")
	(generator_version "10.0")
	(general
		(thickness 1.6)
		(legacy_teardrops no)
	)
	(paper "A4")
	(title_block
		(title "01162023_DA0F0TEBIF0_F0T_Expander_BD_F_brd_V02_OCP.brd")
		(comment 1 "Grand Teton / footprints 1353-1360 of 9728")
	)
	(layers
		(0 "F.Cu" signal "TOP")
		(4 "In1.Cu" signal "GND")
		(6 "In2.Cu" signal "VCC")
		(8 "In3.Cu" signal "VCC1")
		(10 "In4.Cu" signal "GND1")
		(12 "In5.Cu" signal "IN1")
		(14 "In6.Cu" signal "GND2")
		(16 "In7.Cu" signal "IN2")
		(18 "In8.Cu" signal "GND3")
		(20 "In9.Cu" signal "IN3")
		(22 "In10.Cu" signal "GND4")
		(24 "In11.Cu" signal "IN4")
		(26 "In12.Cu" signal "GND5")
		(28 "In13.Cu" signal "IN5")
		(30 "In14.Cu" signal "GND6")
		(32 "In15.Cu" signal "IN6")
		(34 "In16.Cu" signal "GND7")
		(2 "B.Cu" signal "BOTTOM")
		(9 "F.Adhes" user "F.Adhesive")
		(11 "B.Adhes" user "B.Adhesive")
		(13 "F.Paste" user "Package Geometry/Pastemask Top")
		(15 "B.Paste" user "Package Geometry/Pastemask Bottom")
		(5 "F.SilkS" user "Ref Des/Silkscreen Top")
		(7 "B.SilkS" user "Ref Des/Silkscreen Bottom")
		(1 "F.Mask" user "Board Geometry/Soldermask Top")
		(3 "B.Mask" user "Board Geometry/Soldermask Bottom")
		(17 "Dwgs.User" user "User.Drawings")
		(19 "Cmts.User" user "User.Comments")
		(21 "Eco1.User" user "User.Eco1")
		(23 "Eco2.User" user "User.Eco2")
		(25 "Edge.Cuts" user "Board Geometry/Outline")
		(27 "Margin" user)
		(31 "F.CrtYd" user "Package Geometry/Place Bound Top")
		(29 "B.CrtYd" user "Package Geometry/Place Bound Bottom")
		(35 "F.Fab" user "Ref Des/Assembly Top")
		(33 "B.Fab" user "Ref Des/Assembly Bottom")
	)
	(footprint ""
		(layer "F.Cu")
		(at 311.326022 -39.73576 -90)
		(property "Reference" "R5581"
			(at 0 0 270)
			(layer "F.SilkS")
			(hide yes)
			(effects
				(font
					(size 1.27 1.27)
				)
			)
		)
		(property "Value" ""
			(at 0 0 270)
			(layer "F.Fab")
			(effects
				(font
					(size 1.27 1.27)
				)
			)
		)
		(duplicate_pad_numbers_are_jumpers no)
		(fp_line
			(start -0.7874 0.4064)
			(end -0.7874 -0.4064)
			(stroke
				(width 0.1524)
				(type default)
			)
			(layer "F.SilkS")
		)
		(fp_line
			(start 0.7874 0.4064)
			(end -0.7874 0.4064)
			(stroke
				(width 0.1524)
				(type default)
			)
			(layer "F.SilkS")
		)
		(fp_line
			(start -0.7874 -0.4064)
			(end 0.7874 -0.4064)
			(stroke
				(width 0.1524)
				(type default)
			)
			(layer "F.SilkS")
		)
		(fp_line
			(start 0.7874 -0.4064)
			(end 0.7874 0.4064)
			(stroke
				(width 0.1524)
				(type default)
			)
			(layer "F.SilkS")
		)
		(fp_line
			(start -0.67945 0.3048)
			(end -0.67945 -0.305054)
			(stroke
				(width 0.1)
				(type default)
			)
			(layer "F.Fab")
		)
		(fp_line
			(start -0.12065 0.3048)
			(end -0.67945 0.3048)
			(stroke
				(width 0.1)
				(type default)
			)
			(layer "F.Fab")
		)
		(fp_line
			(start 0.120396 0.3048)
			(end 0.120396 0.2794)
			(stroke
				(width 0.1)
				(type default)
			)
			(layer "F.Fab")
		)
		(fp_line
			(start 0.67945 0.3048)
			(end 0.120396 0.3048)
			(stroke
				(width 0.1)
				(type default)
			)
			(layer "F.Fab")
		)
		(fp_line
			(start -0.12065 0.2794)
			(end -0.12065 0.3048)
			(stroke
				(width 0.1)
				(type default)
			)
			(layer "F.Fab")
		)
		(fp_line
			(start 0.120396 0.2794)
			(end -0.12065 0.2794)
			(stroke
				(width 0.1)
				(type default)
			)
			(layer "F.Fab")
		)
		(fp_line
			(start -0.12065 -0.2794)
			(end 0.12065 -0.2794)
			(stroke
				(width 0.1)
				(type default)
			)
			(layer "F.Fab")
		)
		(fp_line
			(start 0.12065 -0.2794)
			(end 0.12065 -0.3048)
			(stroke
				(width 0.1)
				(type default)
			)
			(layer "F.Fab")
		)
		(fp_line
			(start 0.12065 -0.3048)
			(end 0.67945 -0.3048)
			(stroke
				(width 0.1)
				(type default)
			)
			(layer "F.Fab")
		)
		(fp_line
			(start 0.67945 -0.3048)
			(end 0.67945 0.3048)
			(stroke
				(width 0.1)
				(type default)
			)
			(layer "F.Fab")
		)
		(fp_line
			(start -0.67945 -0.305054)
			(end -0.12065 -0.305054)
			(stroke
				(width 0.1)
				(type default)
			)
			(layer "F.Fab")
		)
		(fp_line
			(start -0.12065 -0.305054)
			(end -0.12065 -0.2794)
			(stroke
				(width 0.1)
				(type default)
			)
			(layer "F.Fab")
		)
		(pad "1" smd circle
			(at -0.40005 0 270)
			(size 0 0)
			(layers "F.Cu" "F.Mask" "F.Paste")
			(net "P3V3_AUX")
		)
		(pad "2" smd circle
			(at 0.40005 0 270)
			(size 0 0)
			(layers "F.Cu" "F.Mask" "F.Paste")
			(net "SSD11_AUX_P3V3_EN")
		)
	)
	(footprint ""
		(layer "F.Cu")
		(at 148.260562 -237.923578 180)
		(property "Reference" "C4421"
			(at 0 0 180)
			(layer "F.SilkS")
			(hide yes)
			(effects
				(font
					(size 1.27 1.27)
				)
			)
		)
		(property "Value" ""
			(at 0 0 180)
			(layer "F.Fab")
			(effects
				(font
					(size 1.27 1.27)
				)
			)
		)
		(duplicate_pad_numbers_are_jumpers no)
		(fp_line
			(start 1.524 0.762)
			(end -1.524 0.762)
			(stroke
				(width 0.1524)
				(type default)
			)
			(layer "F.SilkS")
		)
		(fp_line
			(start 1.524 -0.762)
			(end 1.524 0.762)
			(stroke
				(width 0.1524)
				(type default)
			)
			(layer "F.SilkS")
		)
		(fp_line
			(start -1.524 0.762)
			(end -1.524 -0.762)
			(stroke
				(width 0.1524)
				(type default)
			)
			(layer "F.SilkS")
		)
		(fp_line
			(start -1.524 -0.762)
			(end 1.524 -0.762)
			(stroke
				(width 0.1524)
				(type default)
			)
			(layer "F.SilkS")
		)
		(fp_line
			(start 1.1049 0.724916)
			(end 1.1049 -0.724916)
			(stroke
				(width 0.1)
				(type default)
			)
			(layer "F.Fab")
		)
		(fp_line
			(start 1.1049 -0.724916)
			(end -1.1049 -0.724916)
			(stroke
				(width 0.1)
				(type default)
			)
			(layer "F.Fab")
		)
		(fp_line
			(start -1.1049 0.724916)
			(end 1.1049 0.724916)
			(stroke
				(width 0.1)
				(type default)
			)
			(layer "F.Fab")
		)
		(fp_line
			(start -1.1049 -0.724916)
			(end -1.1049 0.724916)
			(stroke
				(width 0.1)
				(type default)
			)
			(layer "F.Fab")
		)
		(pad "1" smd rect
			(at -0.889 0)
			(size 1.016 1.27)
			(layers "F.Cu" "F.Mask" "F.Paste")
			(net "P1V8_PLL0_PEX1")
		)
		(pad "2" smd rect
			(at 0.889 0)
			(size 1.016 1.27)
			(layers "F.Cu" "F.Mask" "F.Paste")
			(net "GND")
		)
	)
	(footprint ""
		(layer "F.Cu")
		(at 15.934182 -135.77697 -90)
		(property "Reference" "PC311"
			(at 0 0 270)
			(layer "F.SilkS")
			(hide yes)
			(effects
				(font
					(size 1.27 1.27)
				)
			)
		)
		(property "Value" ""
			(at 0 0 270)
			(layer "F.Fab")
			(effects
				(font
					(size 1.27 1.27)
				)
			)
		)
		(duplicate_pad_numbers_are_jumpers no)
		(fp_line
			(start -1.524 0.762)
			(end -1.524 -0.762)
			(stroke
				(width 0.1524)
				(type default)
			)
			(layer "F.SilkS")
		)
		(fp_line
			(start 1.524 0.762)
			(end -1.524 0.762)
			(stroke
				(width 0.1524)
				(type default)
			)
			(layer "F.SilkS")
		)
		(fp_line
			(start -1.524 -0.762)
			(end 1.524 -0.762)
			(stroke
				(width 0.1524)
				(type default)
			)
			(layer "F.SilkS")
		)
		(fp_line
			(start 1.524 -0.762)
			(end 1.524 0.762)
			(stroke
				(width 0.1524)
				(type default)
			)
			(layer "F.SilkS")
		)
		(fp_line
			(start -1.1049 0.724916)
			(end 1.1049 0.724916)
			(stroke
				(width 0.1)
				(type default)
			)
			(layer "F.Fab")
		)
		(fp_line
			(start 1.1049 0.724916)
			(end 1.1049 -0.724916)
			(stroke
				(width 0.1)
				(type default)
			)
			(layer "F.Fab")
		)
		(fp_line
			(start -1.1049 -0.724916)
			(end -1.1049 0.724916)
			(stroke
				(width 0.1)
				(type default)
			)
			(layer "F.Fab")
		)
		(fp_line
			(start 1.1049 -0.724916)
			(end -1.1049 -0.724916)
			(stroke
				(width 0.1)
				(type default)
			)
			(layer "F.Fab")
		)
		(pad "1" smd rect
			(at -0.889 0 90)
			(size 1.016 1.27)
			(layers "F.Cu" "F.Mask" "F.Paste")
			(net "P12V_NIC0_R")
		)
		(pad "2" smd rect
			(at 0.889 0 90)
			(size 1.016 1.27)
			(layers "F.Cu" "F.Mask" "F.Paste")
			(net "GND")
		)
	)
	(footprint ""
		(layer "F.Cu")
		(at 236.757718 -204.30236 90)
		(property "Reference" "D7"
			(at 0 0 90)
			(layer "F.SilkS")
			(hide yes)
			(effects
				(font
					(size 1.27 1.27)
				)
			)
		)
		(property "Value" ""
			(at 0 0 90)
			(layer "F.Fab")
			(effects
				(font
					(size 1.27 1.27)
				)
			)
		)
		(duplicate_pad_numbers_are_jumpers no)
		(fp_line
			(start 1.16078 -0.4826)
			(end 1.16078 0.4826)
			(stroke
				(width 0.1524)
				(type default)
			)
			(layer "F.SilkS")
		)
		(fp_line
			(start 1.03378 -0.4826)
			(end 1.03378 0.4826)
			(stroke
				(width 0.1524)
				(type default)
			)
			(layer "F.SilkS")
		)
		(fp_line
			(start 0.90678 -0.4826)
			(end 0.90678 0.4826)
			(stroke
				(width 0.1524)
				(type default)
			)
			(layer "F.SilkS")
		)
		(fp_line
			(start -0.64008 -0.4826)
			(end 1.16078 -0.4826)
			(stroke
				(width 0.1524)
				(type default)
			)
			(layer "F.SilkS")
		)
		(fp_line
			(start -0.79248 -0.4826)
			(end 1.03378 -0.4826)
			(stroke
				(width 0.1524)
				(type default)
			)
			(layer "F.SilkS")
		)
		(fp_line
			(start -0.89408 -0.4826)
			(end 0.90678 -0.4826)
			(stroke
				(width 0.1524)
				(type default)
			)
			(layer "F.SilkS")
		)
		(fp_line
			(start 1.16078 0.4826)
			(end -0.64008 0.4826)
			(stroke
				(width 0.1524)
				(type default)
			)
			(layer "F.SilkS")
		)
		(fp_line
			(start 1.03378 0.4826)
			(end -0.79248 0.4826)
			(stroke
				(width 0.1524)
				(type default)
			)
			(layer "F.SilkS")
		)
		(fp_line
			(start 0.90678 0.4826)
			(end -0.90678 0.4826)
			(stroke
				(width 0.1524)
				(type default)
			)
			(layer "F.SilkS")
		)
		(fp_line
			(start -0.90678 0.4826)
			(end -0.90678 -0.4699)
			(stroke
				(width 0.1524)
				(type default)
			)
			(layer "F.SilkS")
		)
		(fp_line
			(start 0.499872 -0.249936)
			(end 0.499872 0.249936)
			(stroke
				(width 0.1)
				(type default)
			)
			(layer "F.Fab")
		)
		(fp_line
			(start -0.499872 -0.249936)
			(end 0.499872 -0.249936)
			(stroke
				(width 0.1)
				(type default)
			)
			(layer "F.Fab")
		)
		(fp_line
			(start 0.499872 0.249936)
			(end -0.499872 0.249936)
			(stroke
				(width 0.1)
				(type default)
			)
			(layer "F.Fab")
		)
		(fp_line
			(start -0.499872 0.249936)
			(end -0.499872 -0.249936)
			(stroke
				(width 0.1)
				(type default)
			)
			(layer "F.Fab")
		)
		(pad "A" smd rect
			(at -0.47498 0 90)
			(size 0.6096 0.7112)
			(layers "F.Cu" "F.Mask" "F.Paste")
			(net "BMC_HEARTBEAT_N_D")
		)
		(pad "C" smd rect
			(at 0.47498 0 90)
			(size 0.6096 0.7112)
			(layers "F.Cu" "F.Mask" "F.Paste")
			(net "BIC_HEARTBEAT_N")
		)
	)
	(footprint ""
		(layer "F.Cu")
		(at 228.79304 -95.089726)
		(property "Reference" "R5440"
			(at 0 0 0)
			(layer "F.SilkS")
			(hide yes)
			(effects
				(font
					(size 1.27 1.27)
				)
			)
		)
		(property "Value" ""
			(at 0 0 0)
			(layer "F.Fab")
			(effects
				(font
					(size 1.27 1.27)
				)
			)
		)
		(duplicate_pad_numbers_are_jumpers no)
		(fp_line
			(start -0.7874 -0.4064)
			(end 0.7874 -0.4064)
			(stroke
				(width 0.1524)
				(type default)
			)
			(layer "F.SilkS")
		)
		(fp_line
			(start -0.7874 0.4064)
			(end -0.7874 -0.4064)
			(stroke
				(width 0.1524)
				(type default)
			)
			(layer "F.SilkS")
		)
		(fp_line
			(start 0.7874 -0.4064)
			(end 0.7874 0.4064)
			(stroke
				(width 0.1524)
				(type default)
			)
			(layer "F.SilkS")
		)
		(fp_line
			(start 0.7874 0.4064)
			(end -0.7874 0.4064)
			(stroke
				(width 0.1524)
				(type default)
			)
			(layer "F.SilkS")
		)
		(fp_line
			(start -0.67945 -0.305054)
			(end -0.12065 -0.305054)
			(stroke
				(width 0.1)
				(type default)
			)
			(layer "F.Fab")
		)
		(fp_line
			(start -0.67945 0.3048)
			(end -0.67945 -0.305054)
			(stroke
				(width 0.1)
				(type default)
			)
			(layer "F.Fab")
		)
		(fp_line
			(start -0.12065 -0.305054)
			(end -0.12065 -0.2794)
			(stroke
				(width 0.1)
				(type default)
			)
			(layer "F.Fab")
		)
		(fp_line
			(start -0.12065 -0.2794)
			(end 0.12065 -0.2794)
			(stroke
				(width 0.1)
				(type default)
			)
			(layer "F.Fab")
		)
		(fp_line
			(start -0.12065 0.2794)
			(end -0.12065 0.3048)
			(stroke
				(width 0.1)
				(type default)
			)
			(layer "F.Fab")
		)
		(fp_line
			(start -0.12065 0.3048)
			(end -0.67945 0.3048)
			(stroke
				(width 0.1)
				(type default)
			)
			(layer "F.Fab")
		)
		(fp_line
			(start 0.120396 0.2794)
			(end -0.12065 0.2794)
			(stroke
				(width 0.1)
				(type default)
			)
			(layer "F.Fab")
		)
		(fp_line
			(start 0.120396 0.3048)
			(end 0.120396 0.2794)
			(stroke
				(width 0.1)
				(type default)
			)
			(layer "F.Fab")
		)
		(fp_line
			(start 0.12065 -0.3048)
			(end 0.67945 -0.3048)
			(stroke
				(width 0.1)
				(type default)
			)
			(layer "F.Fab")
		)
		(fp_line
			(start 0.12065 -0.2794)
			(end 0.12065 -0.3048)
			(stroke
				(width 0.1)
				(type default)
			)
			(layer "F.Fab")
		)
		(fp_line
			(start 0.67945 -0.3048)
			(end 0.67945 0.3048)
			(stroke
				(width 0.1)
				(type default)
			)
			(layer "F.Fab")
		)
		(fp_line
			(start 0.67945 0.3048)
			(end 0.120396 0.3048)
			(stroke
				(width 0.1)
				(type default)
			)
			(layer "F.Fab")
		)
		(pad "1" smd circle
			(at -0.40005 0)
			(size 0 0)
			(layers "F.Cu" "F.Mask" "F.Paste")
			(net "P3V3_AUX")
		)
		(pad "2" smd circle
			(at 0.40005 0)
			(size 0 0)
			(layers "F.Cu" "F.Mask" "F.Paste")
			(net "PEX_USB_HUB_PSELF")
		)
	)
	(footprint ""
		(layer "F.Cu")
		(at 269.595854 -228.839522)
		(property "Reference" "ME9"
			(at 0 0 0)
			(layer "F.SilkS")
			(hide yes)
			(effects
				(font
					(size 1.27 1.27)
				)
			)
		)
		(property "Value" ""
			(at 0 0 0)
			(layer "F.Fab")
			(effects
				(font
					(size 1.27 1.27)
				)
			)
		)
		(duplicate_pad_numbers_are_jumpers no)
		(fp_line
			(start 0 -5.999988)
			(end 0 -4.475988)
			(stroke
				(width 0.1524)
				(type default)
			)
			(layer "F.SilkS")
		)
		(fp_line
			(start 0 -1.524)
			(end 0 0)
			(stroke
				(width 0.1524)
				(type default)
			)
			(layer "F.SilkS")
		)
		(fp_line
			(start 0 0)
			(end 1.524 0)
			(stroke
				(width 0.1524)
				(type default)
			)
			(layer "F.SilkS")
		)
		(fp_line
			(start 1.524 -5.999988)
			(end 0 -5.999988)
			(stroke
				(width 0.1524)
				(type default)
			)
			(layer "F.SilkS")
		)
		(fp_line
			(start 25.475946 -5.999988)
			(end 26.999946 -5.999988)
			(stroke
				(width 0.1524)
				(type default)
			)
			(layer "F.SilkS")
		)
		(fp_line
			(start 26.999946 -5.999988)
			(end 26.999946 -4.475988)
			(stroke
				(width 0.1524)
				(type default)
			)
			(layer "F.SilkS")
		)
		(fp_line
			(start 26.999946 -1.524)
			(end 26.999946 0)
			(stroke
				(width 0.1524)
				(type default)
			)
			(layer "F.SilkS")
		)
		(fp_line
			(start 26.999946 0)
			(end 25.475946 0)
			(stroke
				(width 0.1524)
				(type default)
			)
			(layer "F.SilkS")
		)
		(fp_text user "S/N"
			(at 0.2032 -4.59105 0)
			(unlocked yes)
			(layer "F.SilkS")
			(effects
				(font
					(size 1.905 1.4224)
					(thickness 0.1524)
				)
				(justify left)
			)
		)
	)
	(footprint ""
		(layer "F.Cu")
		(at 366.920018 -15.649956 180)
		(property "Reference" "H126"
			(at -3.65379 -2.645664 0)
			(unlocked yes)
			(layer "B.SilkS")
			(effects
				(font
					(size 0.7874 0.5842)
					(thickness 0.1524)
				)
				(justify left mirror)
			)
		)
		(property "Value" ""
			(at 0 0 180)
			(layer "F.Fab")
			(effects
				(font
					(size 1.27 1.27)
				)
			)
		)
		(duplicate_pad_numbers_are_jumpers no)
		(pad "1" thru_hole rect
			(at 0 0 180)
			(size 4.2164 5.0038)
			(drill 2.0066
				(offset 0.099822 0)
			)
			(layers "*.Cu" "*.Mask")
			(remove_unused_layers no)
			(net "Net_8537")
			(clearance -0.8509)
			(padstack
				(mode front_inner_back)
				(layer "Inner"
					(shape circle)
					(size 4.0132 4.0132)
					(clearance -0.7493)
				)
				(layer "B.Cu"
					(shape circle)
					(size 4.0132 4.0132)
					(clearance -0.7493)
				)
			)
		)
	)
	(footprint ""
		(layer "F.Cu")
		(at 380.711456 -299.645832 -90)
		(property "Reference" "R4589"
			(at 0 0 270)
			(layer "F.SilkS")
			(hide yes)
			(effects
				(font
					(size 1.27 1.27)
				)
			)
		)
		(property "Value" ""
			(at 0 0 270)
			(layer "F.Fab")
			(effects
				(font
					(size 1.27 1.27)
				)
			)
		)
		(duplicate_pad_numbers_are_jumpers no)
		(fp_line
			(start -0.7874 0.4064)
			(end -0.7874 -0.4064)
			(stroke
				(width 0.1524)
				(type default)
			)
			(layer "F.SilkS")
		)
		(fp_line
			(start 0.7874 0.4064)
			(end -0.7874 0.4064)
			(stroke
				(width 0.1524)
				(type default)
			)
			(layer "F.SilkS")
		)
		(fp_line
			(start -0.7874 -0.4064)
			(end 0.7874 -0.4064)
			(stroke
				(width 0.1524)
				(type default)
			)
			(layer "F.SilkS")
		)
		(fp_line
			(start 0.7874 -0.4064)
			(end 0.7874 0.4064)
			(stroke
				(width 0.1524)
				(type default)
			)
			(layer "F.SilkS")
		)
		(fp_line
			(start -0.67945 0.3048)
			(end -0.67945 -0.305054)
			(stroke
				(width 0.1)
				(type default)
			)
			(layer "F.Fab")
		)
		(fp_line
			(start -0.12065 0.3048)
			(end -0.67945 0.3048)
			(stroke
				(width 0.1)
				(type default)
			)
			(layer "F.Fab")
		)
		(fp_line
			(start 0.120396 0.3048)
			(end 0.120396 0.2794)
			(stroke
				(width 0.1)
				(type default)
			)
			(layer "F.Fab")
		)
		(fp_line
			(start 0.67945 0.3048)
			(end 0.120396 0.3048)
			(stroke
				(width 0.1)
				(type default)
			)
			(layer "F.Fab")
		)
		(fp_line
			(start -0.12065 0.2794)
			(end -0.12065 0.3048)
			(stroke
				(width 0.1)
				(type default)
			)
			(layer "F.Fab")
		)
		(fp_line
			(start 0.120396 0.2794)
			(end -0.12065 0.2794)
			(stroke
				(width 0.1)
				(type default)
			)
			(layer "F.Fab")
		)
		(fp_line
			(start -0.12065 -0.2794)
			(end 0.12065 -0.2794)
			(stroke
				(width 0.1)
				(type default)
			)
			(layer "F.Fab")
		)
		(fp_line
			(start 0.12065 -0.2794)
			(end 0.12065 -0.3048)
			(stroke
				(width 0.1)
				(type default)
			)
			(layer "F.Fab")
		)
		(fp_line
			(start 0.12065 -0.3048)
			(end 0.67945 -0.3048)
			(stroke
				(width 0.1)
				(type default)
			)
			(layer "F.Fab")
		)
		(fp_line
			(start 0.67945 -0.3048)
			(end 0.67945 0.3048)
			(stroke
				(width 0.1)
				(type default)
			)
			(layer "F.Fab")
		)
		(fp_line
			(start -0.67945 -0.305054)
			(end -0.12065 -0.305054)
			(stroke
				(width 0.1)
				(type default)
			)
			(layer "F.Fab")
		)
		(fp_line
			(start -0.12065 -0.305054)
			(end -0.12065 -0.2794)
			(stroke
				(width 0.1)
				(type default)
			)
			(layer "F.Fab")
		)
		(pad "1" smd circle
			(at -0.40005 0 270)
			(size 0 0)
			(layers "F.Cu" "F.Mask" "F.Paste")
			(net "PCEPLL1_VDDA18_PEX3")
		)
		(pad "2" smd circle
			(at 0.40005 0 270)
			(size 0 0)
			(layers "F.Cu" "F.Mask" "F.Paste")
			(net "PCEPLL1_VDDA18_PEX3_R")
		)
	)
)
